FILE_TYPE = CONNECTIVITY;
{Allegro Design Entry HDL 16.6-p007 (v16-6-112F) 10/10/2012}
"PAGE_NUMBER" = 233;
0"NC";
1"PVPP_GHJ\g";
2"GND\g";
3"GND\g";
4"AGND_PVPP_GHJ\g";
5"PVPP_GHJ\g";
6"GND\g";
7"P3V3_STBY\g";
8"GND\g";
9"GND\g";
10"P12V_STBY\g";
11"GND\g";
12"GND\g";
13"GND\g";
14"GND\g";
15"GND\g";
16"GND\g";
17"AGND_PVPP_GHJ\g";
18"AGND_PVPP_GHJ\g";
19"AGND_PVPP_GHJ\g";
20"AGND_PVPP_GHJ\g";
21"AGND_PVPP_GHJ\g";
22"GND\g";
23"AGND_PVPP_GHJ\g";
24"GND\g";
25"GND\g";
26"GND\g";
27"GND\g";
28"GND\g";
29"AGND_PVPP_GHJ\g";
30"FM_PVPP_CPU1_EN";
31"VSENSE_PVPP_GHJ";
32"VR_FB_PVPP_GHJ";
33"VR_COMP_PVPP_GHJ";
34"VR_PVPP_GHJ_PHASE";
35"VR_PVPP_GHJ_SNUB";
36"VR_COMP_PVPP_GHJ_3";
37"VR_COMP_RC_PVPP_GHJ";
38"VR_PVPP_GHJ_BOOT";
39"VR_PVPP_GHJ_BOOT_R";
40"PWRGD_PVPP_GHJ";
41"PWRGD_PVPP_GHJ_R";
42"VR_FET_SW_P12V_STBY_PVPP_GHJ";
43"VR_PVPP_GHJ_ISET";
44"VR_PVPP_GHJ_SS";
45"VR_VB_PVPP_GHJ";
46"FM_PVPP_PVDDQ_CPU1_EN_GHJ";
47"GND\g";
%"CAP"
"1","(-8100,725)","0","mstr_discrete","I109";
;
ROOM"PVPP_KLM_VR"
CDS_LOCATION"C7U4"
$SEC"1"
CDS_SEC"1"
BOM_COST"MEM_VRD_PVPP_AB"
VOLTAGE"4V"
CDS_LIB"mstr_discrete"
LOCATION"C7U4"
PART_NUMBER"E15431-001"
VALUE"10UF"
PACK_TYPE"0603LF"
TOLERANCE"20%"
MATERIAL"X6S";
"A"
$PN"1"1;
"B"
$PN"2"2;
%"PVPP_GHJ"
"1","(-8100,1000)","0","mstr_symbols","I110";
;
HDL_POWER"PVPP_GHJ"
ROOM"PVPP_KLM_VR"
BOM_COST"MEM_VRD_PVPP_AB"
CDS_LIB"mstr_symbols"
BODY_TYPE"PLUMBING"
VOLTAGE"2.5V";
"G\NAC"1;
%"CAP"
"1","(-7850,725)","0","mstr_discrete","I111";
;
BOM_COST"MEM_VRD_PVPP_AB"
CDS_SEC"1"
$SEC"1"
CDS_LOCATION"C7U5"
ROOM"PVPP_KLM_VR"
CDS_LIB"mstr_discrete"
VOLTAGE"4V"
PART_NUMBER"E15431-001"
PACK_TYPE"0603LF"
VALUE"10UF"
LOCATION"C7U5"
TOLERANCE"20%"
MATERIAL"X6S";
"A"
$PN"1"1;
"B"
$PN"2"2;
%"CAP"
"1","(-7575,725)","0","mstr_discrete","I112";
;
BOM_COST"MEM_VRD_PVPP_AB"
CDS_SEC"1"
$SEC"1"
CDS_LOCATION"C7T2"
ROOM"PVPP_KLM_VR"
CDS_LIB"mstr_discrete"
VOLTAGE"4V"
LOCATION"C7T2"
PART_NUMBER"E15431-001"
VALUE"10UF"
PACK_TYPE"0603LF"
TOLERANCE"20%"
MATERIAL"X6S";
"A"
$PN"1"1;
"B"
$PN"2"2;
%"CAP"
"1","(-7325,700)","0","mstr_discrete","I113";
;
BOM_COST"MEM_VRD_PVPP_AB"
CDS_SEC"1"
$SEC"1"
CDS_LOCATION"C7T3"
ROOM"PVPP_KLM_VR"
CDS_LIB"mstr_discrete"
VOLTAGE"4V"
LOCATION"C7T3"
PART_NUMBER"E15431-001"
VALUE"10UF"
PACK_TYPE"0603LF"
TOLERANCE"20%"
MATERIAL"X6S";
"A"
$PN"1"1;
"B"
$PN"2"2;
%"CAP"
"1","(-7050,725)","0","mstr_discrete","I115";
;
BOM_COST"MEM_VRD_PVPP_AB"
CDS_SEC"1"
$SEC"1"
CDS_LOCATION"C7U6"
ROOM"PVPP_KLM_VR"
CDS_LIB"mstr_discrete"
VOLTAGE"4V"
LOCATION"C7U6"
PART_NUMBER"E15431-001"
VALUE"10UF"
PACK_TYPE"0603LF"
TOLERANCE"20%"
MATERIAL"X6S";
"A"
$PN"1"1;
"B"
$PN"2"2;
%"CAP"
"1","(-6750,725)","0","mstr_discrete","I116";
;
CDS_SEC"1"
$SEC"1"
BOM_COST"MEM_VRD_PVPP_AB"
ROOM"PVPP_KLM_VR"
CDS_LOCATION"C3F3"
CDS_LIB"mstr_discrete"
VOLTAGE"4V"
LOCATION"C3F3"
PART_NUMBER"E15431-001"
VALUE"10UF"
TOLERANCE"20%"
PACK_TYPE"0603LF"
MATERIAL"X6S";
"A"
$PN"1"1;
"B"
$PN"2"2;
%"CAP"
"1","(-6475,725)","0","mstr_discrete","I117";
;
CDS_SEC"1"
$SEC"1"
BOM_COST"MEM_VRD_PVPP_AB"
ROOM"PVPP_KLM_VR"
CDS_LOCATION"C3F4"
CDS_LIB"mstr_discrete"
VOLTAGE"4V"
PART_NUMBER"E15431-001"
LOCATION"C3F4"
VALUE"10UF"
TOLERANCE"20%"
PACK_TYPE"0603LF"
MATERIAL"X6S";
"A"
$PN"1"1;
"B"
$PN"2"2;
%"CAP"
"1","(-6175,725)","0","mstr_discrete","I118";
;
VOLTAGE"4V"
BOM_COST"MEM_VRD_PVPP_AB"
CDS_SEC"1"
$SEC"1"
CDS_LOCATION"C3G3"
ROOM"PVPP_KLM_VR"
CDS_LIB"mstr_discrete"
PART_NUMBER"E15431-001"
LOCATION"C3G3"
VALUE"10UF"
TOLERANCE"20%"
PACK_TYPE"0603LF"
MATERIAL"X6S";
"A"
$PN"1"1;
"B"
$PN"2"2;
%"CAP"
"1","(-5875,725)","0","mstr_discrete","I132";
;
BOM_COST"MEM_VRD_PVPP_AB"
CDS_SEC"1"
$SEC"1"
CDS_LOCATION"C3G7"
ROOM"PVPP_KLM_VR"
VOLTAGE"4V"
CDS_LIB"mstr_discrete"
PART_NUMBER"E15431-001"
LOCATION"C3G7"
VALUE"10UF"
TOLERANCE"20%"
PACK_TYPE"0603LF"
MATERIAL"X6S";
"A"
$PN"1"1;
"B"
$PN"2"2;
%"CAP"
"1","(-5600,700)","0","mstr_discrete","I133";
;
CDS_SEC"1"
$SEC"1"
ROOM"PVPP_KLM_VR"
BOM_COST"MEM_VRD_PVPP_AB"
CDS_LOCATION"C3G4"
CDS_LIB"mstr_discrete"
VOLTAGE"4V"
PART_NUMBER"E15431-001"
LOCATION"C3G4"
VALUE"10UF"
TOLERANCE"20%"
MATERIAL"X6S"
PACK_TYPE"0603LF";
"A"
$PN"1"1;
"B"
$PN"2"2;
%"GND"
"1","(-5150,400)","0","mstr_symbols","I134";
;
SIZE"1B"
HDL_POWER"GND"
BOM_COST"MEM_VRD_PVPP_AB"
VOLTAGE"0"
CDS_LIB"mstr_symbols"
BODY_TYPE"PLUMBING"
ROOM"PVPP_KLM_VR";
"A\NAC"2;
%"CAP"
"1","(-5325,700)","0","mstr_discrete","I135";
;
CDS_SEC"1"
$SEC"1"
ROOM"PVPP_KLM_VR"
CDS_LOCATION"C3G8"
BOM_COST"MEM_VRD_PVPP_AB"
CDS_LIB"mstr_discrete"
VOLTAGE"4V"
PART_NUMBER"E15431-001"
PACK_TYPE"0603LF"
LOCATION"C3G8"
VALUE"10UF"
MATERIAL"X6S"
TOLERANCE"20%";
"A"
$PN"1"1;
"B"
$PN"2"2;
%"CAP"
"1","(-5075,725)","0","mstr_discrete","I136";
;
CDS_SEC"1"
SEC"1"
BOM_COST"MEM_VRD_PVPP_AB"
SEC_TYPE"0603LF"
ROOM"PVPP_KLM_VR"
CDS_LOCATION"C7U3"
VOLTAGE"4V"
CDS_LIB"mstr_discrete"
PACK_TYPE"0603LF"
PART_NUMBER"E15431-001"
LOCATION"C7U3"
VALUE"10UF"
MATERIAL"X6S"
TOLERANCE"20%";
"A"
$PN"1"1;
"B"
$PN"2"2;
%"GND"
"1","(-1400,450)","0","mstr_symbols","I156";
;
HDL_POWER"GND"
VOLTAGE"0"
SIZE"1B"
CDS_LIB"mstr_symbols"
BODY_TYPE"PLUMBING"
ROOM"PVPP_KLM_VR"
BOM_COST"PVPP_KLM_VR";
"A\NAC"3;
%"RES"
"1","(-1100,550)","0","mstr_discrete","I157";
;
CDS_LOCATION"R4G25"
$SEC"1"
CDS_SEC"1"
ROOM"PVPP_KLM_VR"
CDS_LIB"mstr_discrete"
LOCATION"R4G25"
PART_NUMBER"G21497-005"
MATERIAL"CHIP"
VALUE"0.0"
TOLERANCE"5%"
PACK_TYPE"0402"
WATTAGE"1/16W";
"B"
$PN"2"4;
"A"
$PN"1"3;
%"AGND_SCSI"
"1","(-850,450)","0","mstr_symbols","I158";
;
BOM_COST"PVPP_KLM_VR"
ROOM"PVPP_KLM_VR"
BODY_TYPE"PLUMBING"
VOLTAGE"0.0V"
CDS_LIB"mstr_symbols"
HDL_POWER"AGND_PVPP_GHJ";
"A"4;
%"PVPP_GHJ"
"1","(-725,3825)","0","mstr_symbols","I174";
;
ROOM"PVPP_KLM_VR"
HDL_POWER"PVPP_GHJ"
BOM_COST"PVPP_KLM_VR"
CDS_LIB"mstr_symbols"
VOLTAGE"2.5V"
BODY_TYPE"PLUMBING";
"G\NAC"5;
%"GND"
"1","(-7175,1725)","0","mstr_symbols","I180";
;
SIZE"1B"
HDL_POWER"GND"
BODY_TYPE"PLUMBING"
CDS_LIB"mstr_symbols"
VOLTAGE"0"
ROOM"PVPP_KLM_VR"
BOM_COST"PVPP_KLM_VR"
BOM"SYSB_CPLD";
"A\NAC"6;
%"RES"
"2","(-7175,2125)","0","mstr_discrete","I182";
;
BOM_COST"PVPP_KLM_VR"
BOM"SYSB_CPLD"
CDS_SEC"1"
$SEC"1"
CDS_LOCATION"R4G5"
ROOM"PVPP_KLM_VR"
CDS_LIB"mstr_discrete"
LOCATION"R4G5"
VALUE"10.0K"
TOLERANCE"1%"
MATERIAL"CHIP"
WATTAGE"1/16W"
PART_NUMBER"G21796-016"
PACK_TYPE"0402";
"A"
$PN"1"30;
"B"
$PN"2"6;
%"CAP"
"1","(-6500,2200)","2","mstr_discrete","I183";
;
FIN"VR_1P2"
REUSE_ID"1"
CDS_SEC"1"
$SEC"1"
CDS_LOCATION"C4G7"
CDS_LIB"mstr_discrete"
BOM_COST"PVPP_KLM_VR"
ROOM"PVPP_KLM_VR"
VOLTAGE"50V"
TOLERANCE"10%"
MATERIAL"EMPTY"
LOCATION"C4G7"
PART_NUMBER"A36096-046"
VALUE"1000PF"
PACK_TYPE"0402LF";
"A"
$PN"1"30;
"B"
$PN"2"17;
%"RES"
"2","(-4675,1500)","2","mstr_discrete","I184";
;
CDS_SEC"1"
SEC_TYPE"0402"
SEC"1"
CDS_LOCATION"R4G11"
BOM_COST"PVPP_KLM_VR"
CDS_LIB"mstr_discrete"
ROOM"PVPP_KLM_VR"
LOCATION"R4G11"
VALUE"7.87K"
TOLERANCE"1.0%"
PACK_TYPE"0402"
MATERIAL"CHIP"
WATTAGE"1/16W"
PART_NUMBER"G21796-242";
"A"
$PN"1"43;
"B"
$PN"2"20;
%"RES"
"2","(-4150,1100)","0","mstr_discrete","I185";
;
CDS_SEC"1"
BOM_COST"PVPP_KLM_VR"
ROOM"PVPP_KLM_VR"
REUSE_ID"21"
SEC_TYPE"0402"
SEC"1"
CDS_LIB"mstr_discrete"
CDS_LOCATION"R4G14"
LOCATION"R4G14"
PART_NUMBER"G21796-026"
VALUE"1.00K"
TOLERANCE"1%"
PACK_TYPE"0402"
MATERIAL"CHIP"
WATTAGE"1/16W";
"A"
$PN"1"7;
"B"
$PN"2"41;
%"P3V3_STBY"
"1","(-4150,1375)","0","mstr_symbols","I186";
;
VOLTAGE"+3.3V"
CDS_LIB"mstr_symbols"
SIZE"1B"
BODY_TYPE"PLUMBING"
HDL_POWER"P3V3_STBY";
"G\NAC"7;
%"CAP"
"1","(-5525,2250)","0","mstr_discrete","I187";
;
CDS_SEC"1"
SEC"1"
CDS_LOCATION"C6U6"
ROOM"PVPP_KLM_VR"
BOM_COST"PVPP_KLM_VR"
SEC_TYPE"0603"
REUSE_ID"26"
CDS_LIB"mstr_discrete"
PART_NUMBER"E15431-003"
LOCATION"C6U6"
TOLERANCE"10%"
VALUE"4.7UF"
VOLTAGE"6.3V"
PACK_TYPE"0603"
MATERIAL"X6S";
"A"
$PN"1"45;
"B"
$PN"2"18;
%"GND"
"1","(-7025,3800)","0","mstr_symbols","I188";
;
HDL_POWER"GND"
VOLTAGE"0"
CDS_LIB"mstr_symbols"
SIZE"1B"
BODY_TYPE"PLUMBING"
BOM_COST"PVPP_KLM_VR"
ROOM"PVPP_KLM_VR";
"A\NAC"8;
%"CAP"
"1","(-7025,4000)","0","mstr_discrete","I189";
;
CDS_SEC"1"
$SEC"1"
CDS_LOCATION"C4G5"
BOM_COST"PVPP_KLM_VR"
CDS_LIB"mstr_discrete"
ROOM"PVPP_KLM_VR"
LOCATION"C4G5"
PART_NUMBER"D38464-007"
VALUE"47UF"
TOLERANCE"20%"
PACK_TYPE"1210"
VOLTAGE"16V"
MATERIAL"X6S";
"A"
$PN"1"42;
"B"
$PN"2"8;
%"CAP"
"1","(-5000,2025)","0","mstr_discrete","I194";
;
CDS_SEC"1"
ROOM"PVPP_KLM_VR"
CDS_LOCATION"C4G8"
SEC"1"
BOM_COST"PVPP_KLM_VR"
REUSE_ID"26"
SEC_TYPE"0402"
CDS_LIB"mstr_discrete"
VALUE"0.027UF"
LOCATION"C4G8"
VOLTAGE"16V"
PART_NUMBER"A36096-129"
TOLERANCE"10%"
PACK_TYPE"0402"
MATERIAL"X7R";
"A"
$PN"1"44;
"B"
$PN"2"19;
%"GND"
"1","(-4875,3675)","0","mstr_symbols","I195";
;
SIZE"1B"
HDL_POWER"GND"
BODY_TYPE"PLUMBING"
CDS_LIB"mstr_symbols"
VOLTAGE"0"
ROOM"PVPP_KLM_VR"
BOM_COST"PVPP_KLM_VR";
"A\NAC"9;
%"CAP"
"1","(-4875,4000)","0","mstr_discrete","I196";
;
FIN"VR_1P2"
REUSE_ID"1"
CDS_SEC"1"
$SEC"1"
CDS_LOCATION"C4G4"
BOM_COST"PVPP_KLM_VR"
CDS_LIB"mstr_discrete"
ROOM"PVPP_KLM_VR"
LOCATION"C4G4"
PART_NUMBER"D97712-011"
PACK_TYPE"0402"
TOLERANCE"10%"
VOLTAGE"16V"
MATERIAL"X6S"
VALUE"1.0UF";
"A"
$PN"1"42;
"B"
$PN"2"9;
%"P12V_STBY"
"1","(-7400,4350)","0","mstr_symbols","I197";
;
SIZE"1B"
CDS_LIB"mstr_symbols"
VOLTAGE"12.0V"
BODY_TYPE"PLUMBING"
HDL_POWER"P12V_STBY";
"G\NAC"10;
%"FERRITE"
"1","(-7225,4150)","0","mstr_discrete","I198";
;
CDS_SEC"1"
SEC"1"
SEC_TYPE"SM"
ROOM"PVPP_KLM_VR"
CDS_LIB"mstr_discrete"
TOLERANCE"1%"
CDS_LOCATION"FB4G1"
PART_NUMBER"656554-051"
LOCATION"FB4G1"
PACK_TYPE"SM"
MATERIAL"FB"
VALUE"22";
"A"
$PN"1"10;
"B"
$PN"2"42;
%"RES"
"1","(-4000,4050)","0","mstr_discrete","I199";
;
CDS_LOCATION"R4G24"
SPOF"TRUE"
REUSE_ID"13"
CDS_SEC"1"
$SEC"1"
CDS_LIB"mstr_discrete"
BOM_COST"PVPP_KLM_VR"
ROOM"PVPP_KLM_VR"
LOCATION"R4G24"
PACK_TYPE"0402"
MATERIAL"CHIP"
TOLERANCE"5%"
PART_NUMBER"G21497-005"
WATTAGE"1/16W"
VALUE"0.0";
"B"
$PN"2"39;
"A"
$PN"1"38;
%"GND"
"1","(-3800,325)","0","mstr_symbols","I200";
;
HDL_POWER"GND"
VOLTAGE"0"
CDS_LIB"mstr_symbols"
SIZE"1B"
BODY_TYPE"PLUMBING"
ROOM"PVPP_KLM_VR"
BOM_COST"PVPP_KLM_VR";
"A\NAC"11;
%"CAP"
"1","(-3800,575)","0","mstr_discrete","I201";
;
$SEC"1"
CDS_SEC"1"
REUSE_ID"17"
BOM_COST"PVPP_KLM_VR"
CDS_LIB"mstr_discrete"
CDS_LOCATION"C4G9"
ROOM"PVPP_KLM_VR"
PART_NUMBER"A36096-046"
VALUE"1000PF"
PACK_TYPE"0402LF"
TOLERANCE"10%"
LOCATION"C4G9"
VOLTAGE"50V"
MATERIAL"X7R";
"A"
$PN"1"41;
"B"
$PN"2"11;
%"GND"
"1","(-3000,1775)","0","mstr_symbols","I203";
;
SIZE"1B"
HDL_POWER"GND"
VOLTAGE"0"
CDS_LIB"mstr_symbols"
BODY_TYPE"PLUMBING"
ROOM"PVPP_KLM_VR"
BOM_COST"PVPP_KLM_VR";
"A\NAC"12;
%"GND"
"1","(-2575,3000)","0","mstr_symbols","I207";
;
HDL_POWER"GND"
VOLTAGE"0"
CDS_LIB"mstr_symbols"
SIZE"1B"
BODY_TYPE"PLUMBING"
ROOM"PVPP_KLM_VR"
BOM_COST"PVPP_KLM_VR";
"A\NAC"13;
%"RES"
"2","(-2575,3200)","0","mstr_discrete","I208";
;
REUSE_ID"29"
CDS_SEC"1"
BOM_COST"PVPP_KLM_VR"
$SEC"1"
ROOM"PVPP_KLM_VR"
CDS_LOCATION"R4F6"
CDS_LIB"mstr_discrete"
MATERIAL"EMPTY"
LOCATION"R4F6"
VALUE"2.2"
TOLERANCE"5%"
PACK_TYPE"0402"
WATTAGE"1/16W"
PART_NUMBER"G21497-016";
"A"
$PN"1"35;
"B"
$PN"2"13;
%"CAP"
"1","(-2575,3550)","0","mstr_discrete","I209";
;
BOM_COST"PVPP_KLM_VR"
REUSE_ID"26"
CDS_SEC"1"
$SEC"1"
CDS_LOCATION"C4F12"
ROOM"PVPP_KLM_VR"
CDS_LIB"mstr_discrete"
VALUE"3300PF"
LOCATION"C4F12"
MATERIAL"EMPTY"
PART_NUMBER"A36096-091"
PACK_TYPE"0402LF"
TOLERANCE"10%"
VOLTAGE"50V";
"A"
$PN"1"34;
"B"
$PN"2"35;
%"GND"
"1","(-2000,3275)","0","mstr_symbols","I210";
;
HDL_POWER"GND"
VOLTAGE"0"
SIZE"1B"
CDS_LIB"mstr_symbols"
BODY_TYPE"PLUMBING"
ROOM"PVPP_KLM_VR"
BOM_COST"PVPP_KLM_VR";
"A\NAC"14;
%"RES"
"2","(-2000,3525)","0","mstr_discrete","I211";
;
REUSE_ID"34"
CDS_SEC"1"
$SEC"1"
BOM_COST"PVPP_KLM_VR"
ROOM"PVPP_KLM_VR"
CDS_LOCATION"R4G6"
CDS_LIB"mstr_discrete"
LOCATION"R4G6"
VALUE"120.0"
PART_NUMBER"G22026-003"
WATTAGE"1/10W"
MATERIAL"CHIP"
PACK_TYPE"0603"
TOLERANCE"1%";
"A"
$PN"1"5;
"B"
$PN"2"14;
%"GND"
"1","(-1675,3300)","0","mstr_symbols","I216";
;
HDL_POWER"GND"
VOLTAGE"0"
CDS_LIB"mstr_symbols"
SIZE"1B"
BODY_TYPE"PLUMBING"
ROOM"PVPP_KLM_VR"
BOM_COST"PVPP_KLM_VR";
"A\NAC"15;
%"CAPP"
"1","(-1675,3525)","0","mstr_discrete","I217";
;
CDS_LOCATION"C4F7"
$SEC"1"
CDS_SEC"1"
REUSE_ID"28"
BOM_COST"PVPP_KLM_VR"
CDS_LIB"mstr_discrete"
ROOM"PVPP_KLM_VR"
LOCATION"C4F7"
PART_NUMBER"724613-042"
VALUE"330UF"
PACK_TYPE"7343LF"
VOLTAGE"6.3V"
MATERIAL"POSCAP"
TOLERANCE"20%";
"B"
$PN"2"15;
"A"
$PN"1"5;
%"GND"
"1","(-1075,3325)","0","mstr_symbols","I220";
;
SIZE"1B"
HDL_POWER"GND"
VOLTAGE"0"
CDS_LIB"mstr_symbols"
BODY_TYPE"PLUMBING"
ROOM"PVPP_KLM_VR"
BOM_COST"PVPP_KLM_VR";
"A\NAC"16;
%"CAP"
"1","(-1075,3525)","0","mstr_discrete","I221";
;
CDS_LOCATION"C6U3"
$SEC"1"
CDS_SEC"1"
REUSE_ID"33"
ROOM"PVPP_KLM_VR"
CDS_LIB"mstr_discrete"
BOM_COST"PVPP_KLM_VR"
LOCATION"C6U3"
PART_NUMBER"C95333-006"
VALUE"47UF"
TOLERANCE"20%"
PACK_TYPE"0805"
VOLTAGE"4V"
MATERIAL"X6S";
"A"
$PN"1"5;
"B"
$PN"2"16;
%"GND"
"1","(-775,3350)","0","mstr_symbols","I222";
;
SIZE"1B"
VOLTAGE"0"
CDS_LIB"mstr_symbols"
BODY_TYPE"PLUMBING"
HDL_POWER"GND"
ROOM"PVPP_KLM_VR"
BOM_COST"PVPP_KLM_VR";
"A\NAC"47;
%"CAP"
"1","(-775,3500)","0","mstr_discrete","I223";
;
REUSE_ID"33"
CDS_SEC"1"
$SEC"1"
CDS_LOCATION"C6U2"
ROOM"PVPP_KLM_VR"
CDS_LIB"mstr_discrete"
BOM_COST"PVPP_KLM_VR"
PART_NUMBER"C95333-006"
LOCATION"C6U2"
PACK_TYPE"0805"
TOLERANCE"20%"
VALUE"47UF"
VOLTAGE"4V"
MATERIAL"X6S";
"A"
$PN"1"5;
"B"
$PN"2"47;
%"CAP"
"2","(-3300,4050)","2","mstr_discrete","I224";
;
CDS_LOCATION"C4G26"
REUSE_ID"27"
SPOF"TRUE"
BOM_COST"PVPP_KLM_VR"
CDS_SEC"1"
$SEC"1"
ROOM"PVPP_KLM_VR"
CDS_LIB"mstr_discrete"
LOCATION"C4G26"
PART_NUMBER"602433-020"
TOLERANCE"10%"
VALUE"0.1UF"
MATERIAL"X7R"
VOLTAGE"25V"
PACK_TYPE"0603LF";
"A"
$PN"1"34;
"B"
$PN"2"39;
%"NCP3232L"
"1","(-3725,2725)","0","mstr_vreg","I225";
;
CDS_SEC"1"
CDS_LIB"mstr_vreg"
CDS_LMAN_SYM_OUTLINE"-450,850,450,-900"
PACK_TYPE"SM"
SEC_TYPE"SM"
SEC"1"
CDS_LOCATION"EU4G1"
LOCATION"EU4G1"
PART_NUMBER"H86355-001"
MATERIAL"IC";
"PG"
$PN"7"41;
"PGND<0>"
$PN"16"12;
"PGND<1>"
$PN"17"12;
"PGND<2>"
$PN"18"12;
"PGND<3>"
$PN"19"12;
"PGND<4>"
$PN"20"12;
"PGND<5>"
$PN"21"12;
"PGND<6>"
$PN"22"12;
"PGND<8>"
$PN"24"12;
"PGND<7>"
$PN"23"12;
"PGND<9>"
$PN"25"12;
"PGND<10>"
$PN"26"12;
"PGND<11>"
$PN"27"12;
"PGND<12>"
$PN"28"12;
"PGND<13>"
$PN"37"12;
"GND"
$PN"41"12;
"AGND"
$PN"5"21;
"EN"
$PN"40"46;
"SS"
$PN"1"44;
"ISET"
$PN"4"43;
"OTS"
$PN"6"23;
"VIN<6>"
$PN"14"42;
"VIN<7>"
$PN"42"42;
"VCC"
$PN"39"42;
"VIN<1>"
$PN"9"42;
"VIN<5>"
$PN"13"42;
"VIN<4>"
$PN"12"42;
"VIN<3>"
$PN"11"42;
"VIN<2>"
$PN"10"42;
"VIN<0>"
$PN"8"42;
"VB"
$PN"38"45;
"COMP"
$PN"3"36;
"FB"
$PN"2"32;
"VSWH<1>"
$PN"29"34;
"VSWH<0>"
$PN"15"34;
"VSW"
$PN"35"34;
"VSWH<2>"
$PN"30"34;
"VSWH<3>"
$PN"31"34;
"VSWH<4>"
$PN"32"34;
"VSWH<5>"
$PN"33"34;
"VSWH<6>"
$PN"34"34;
"BST"
$PN"36"38;
"VSWH<7>"
$PN"43"34;
%"AGND_SCSI"
"1","(-6500,1800)","0","mstr_symbols","I226";
;
ROOM"PVPP_KLM_VR"
BODY_TYPE"PLUMBING"
CDS_LIB"mstr_symbols"
BOM_COST"PVPP_KLM_VR"
VOLTAGE"0.0V"
HDL_POWER"AGND_PVPP_GHJ";
"A"17;
%"AGND_SCSI"
"1","(-5525,1950)","0","mstr_symbols","I227";
;
BODY_TYPE"PLUMBING"
CDS_LIB"mstr_symbols"
VOLTAGE"0.0V"
ROOM"PVPP_KLM_VR"
BOM_COST"PVPP_KLM_VR"
HDL_POWER"AGND_PVPP_GHJ";
"A"18;
%"AGND_SCSI"
"1","(-5000,1800)","0","mstr_symbols","I228";
;
CDS_LIB"mstr_symbols"
VOLTAGE"0.0V"
BODY_TYPE"PLUMBING"
ROOM"PVPP_KLM_VR"
BOM_COST"PVPP_KLM_VR"
HDL_POWER"AGND_PVPP_GHJ";
"A"19;
%"AGND_SCSI"
"1","(-4675,1200)","0","mstr_symbols","I229";
;
VOLTAGE"0"
CDS_LIB"mstr_symbols"
BODY_TYPE"PLUMBING"
HDL_POWER"AGND_PVPP_GHJ";
"A"20;
%"AGND_SCSI"
"1","(-4300,1700)","0","mstr_symbols","I230";
;
VOLTAGE"0.0V"
CDS_LIB"mstr_symbols"
BODY_TYPE"PLUMBING"
ROOM"PVPP_KLM_VR"
BOM_COST"PVPP_KLM_VR"
HDL_POWER"AGND_PVPP_GHJ";
"A"21;
%"CAP_A"
"1","(-5050,3325)","0","dev_discrete","I242";
;
CDS_LOCATION"C6U5"
CDS_SEC"1"
SEC_TYPE"0402V"
SEC"1"
CDS_LIB"dev_discrete"
PART_NUMBER"A36096-030"
VALUE"0.1UF"
PACK_TYPE"0402V"
LOCATION"C6U5"
VOLTAGE"16V"
TOLERANCE"10%"
MATERIAL"X7R";
"B"
$PN"2"22;
"A"
$PN"1"42;
%"GND"
"1","(-5050,3100)","0","mstr_symbols","I243";
;
HDL_POWER"GND"
VOLTAGE"0"
CDS_LIB"mstr_symbols"
SIZE"1B"
BODY_TYPE"PLUMBING"
ROOM"PVPP_KLM_VR"
BOM_COST"PVPP_KLM_VR";
"A\NAC"22;
%"AGND_SCSI"
"1","(-5300,2575)","0","mstr_symbols","I244";
;
CDS_LIB"mstr_symbols"
BOM_COST"PVPP_KLM_VR"
ROOM"PVPP_KLM_VR"
BODY_TYPE"PLUMBING"
VOLTAGE"0.0V"
HDL_POWER"AGND_PVPP_GHJ";
"A"23;
%"GND"
"1","(-1375,3325)","0","mstr_symbols","I246";
;
HDL_POWER"GND"
VOLTAGE"0"
CDS_LIB"mstr_symbols"
SIZE"1B"
BODY_TYPE"PLUMBING"
ROOM"PVPP_KLM_VR"
BOM_COST"PVPP_KLM_VR";
"A\NAC"24;
%"RES"
"1","(-3375,825)","0","mstr_discrete","I247";
;
CDS_SEC"1"
SEC_TYPE"0402"
SEC"1"
ROOM"PVPP_GHJ_VR"
CDS_LOCATION"R4G12"
CDS_LIB"mstr_discrete"
PACK_TYPE"0402"
LOCATION"R4G12"
PART_NUMBER"G21796-250"
TOLERANCE"1.0%"
MATERIAL"CHIP"
WATTAGE"1/16W"
VALUE"22.1";
"B"
$PN"2"40;
"A"
$PN"1"41;
%"CAP"
"1","(-6700,3975)","0","mstr_discrete","I248";
;
CDS_SEC"1"
SEC_TYPE"0805"
SEC"1"
CDS_LOCATION"C6U4"
CDS_LIB"mstr_discrete"
LOCATION"C6U4"
PART_NUMBER"C95333-007"
VALUE"10UF"
TOLERANCE"10%"
PACK_TYPE"0805"
VOLTAGE"16V"
MATERIAL"X6S";
"A"
$PN"1"42;
"B"
$PN"2"25;
%"GND"
"1","(-6700,3775)","0","mstr_symbols","I249";
;
SIZE"1B"
HDL_POWER"GND"
VOLTAGE"0"
CDS_LIB"mstr_symbols"
BODY_TYPE"PLUMBING"
BOM_COST"PVPP_KLM_VR"
ROOM"PVPP_KLM_VR";
"A\NAC"25;
%"GND"
"1","(-6300,3775)","0","mstr_symbols","I250";
;
HDL_POWER"GND"
VOLTAGE"0"
SIZE"1B"
CDS_LIB"mstr_symbols"
BODY_TYPE"PLUMBING"
ROOM"PVPP_KLM_VR"
BOM_COST"PVPP_KLM_VR";
"A\NAC"26;
%"GND"
"1","(-5875,3775)","0","mstr_symbols","I251";
;
HDL_POWER"GND"
VOLTAGE"0"
SIZE"1B"
CDS_LIB"mstr_symbols"
BODY_TYPE"PLUMBING"
ROOM"PVPP_KLM_VR"
BOM_COST"PVPP_KLM_VR";
"A\NAC"27;
%"GND"
"1","(-5450,3775)","0","mstr_symbols","I252";
;
SIZE"1B"
HDL_POWER"GND"
VOLTAGE"0"
CDS_LIB"mstr_symbols"
BODY_TYPE"PLUMBING"
ROOM"PVPP_KLM_VR"
BOM_COST"PVPP_KLM_VR";
"A\NAC"28;
%"CAP"
"1","(-6300,3975)","0","mstr_discrete","I253";
;
CDS_SEC"1"
SEC_TYPE"0805"
SEC"1"
CDS_LOCATION"C4G2"
CDS_LIB"mstr_discrete"
LOCATION"C4G2"
PART_NUMBER"C95333-007"
VALUE"10UF"
PACK_TYPE"0805"
MATERIAL"X6S"
VOLTAGE"16V"
TOLERANCE"10%";
"A"
$PN"1"42;
"B"
$PN"2"26;
%"CAP"
"1","(-5875,3975)","0","mstr_discrete","I254";
;
CDS_SEC"1"
SEC_TYPE"0805"
SEC"1"
CDS_LOCATION"C6U7"
CDS_LIB"mstr_discrete"
LOCATION"C6U7"
PART_NUMBER"C95333-007"
MATERIAL"X6S"
VOLTAGE"16V"
TOLERANCE"10%"
VALUE"10UF"
PACK_TYPE"0805";
"A"
$PN"1"42;
"B"
$PN"2"27;
%"CAP"
"1","(-5450,3975)","0","mstr_discrete","I255";
;
CDS_SEC"1"
SEC_TYPE"0805"
SEC"1"
CDS_LOCATION"C6U8"
CDS_LIB"mstr_discrete"
LOCATION"C6U8"
PART_NUMBER"C95333-007"
VALUE"10UF"
TOLERANCE"10%"
PACK_TYPE"0805"
VOLTAGE"16V"
MATERIAL"X6S";
"A"
$PN"1"42;
"B"
$PN"2"28;
%"CAPP"
"1","(-1375,3500)","0","mstr_discrete","I256";
;
CDS_SEC"1"
CDS_LOCATION"C4F11"
SEC"1"
SEC_TYPE"7343"
CDS_LIB"mstr_discrete"
LOCATION"C4F11"
PART_NUMBER"724613-067"
VALUE"220UF"
TOLERANCE"20%"
PACK_TYPE"7343"
VOLTAGE"4V"
MATERIAL"POSCAP";
"B"
$PN"2"24;
"A"
$PN"1"5;
%"RES"
"2","(-950,2475)","0","mstr_discrete","I266";
;
CDS_SEC"1"
ROOM"PVPP_KLM_VR"
CDS_LOCATION"R4G10"
SEC"1"
BOM_COST"PVPP_KLM_VR"
REUSE_ID"9"
SEC_TYPE"0402"
SPOF"TRUE"
CDS_LIB"mstr_discrete"
LOCATION"R4G10"
VALUE"1.0K"
PART_NUMBER"G85996-004"
WATTAGE"1/16W"
TOLERANCE"0.1%"
PACK_TYPE"0402"
MATERIAL"CHIP";
"A"
$PN"1"31;
"B"
$PN"2"33;
%"CAP"
"1","(-950,1925)","0","mstr_discrete","I267";
;
CDS_SEC"1"
REUSE_ID"26"
SPOF"TRUE"
SEC_TYPE"0402LF"
SEC"1"
BOM_COST"PVPP_KLM_VR"
ROOM"PVPP_KLM_VR"
CDS_LOCATION"C4G11"
CDS_LIB"mstr_discrete"
LOCATION"C4G11"
PACK_TYPE"0402LF"
VALUE"2200PF"
PART_NUMBER"A36096-075"
VOLTAGE"50V"
MATERIAL"X7R"
TOLERANCE"10%";
"A"
$PN"1"33;
"B"
$PN"2"32;
%"RES"
"2","(-1275,1400)","0","mstr_discrete","I269";
;
CDS_SEC"1"
REUSE_ID"7"
SPOF"TRUE"
$SEC"1"
CDS_LOCATION"R4G9"
CDS_LIB"mstr_discrete"
ROOM"PVPP_KLM_VR"
BOM_COST"PVPP_KLM_VR"
PART_NUMBER"G21796-146"
LOCATION"R4G9"
TOLERANCE"1%"
VALUE"6.34K"
MATERIAL"CHIP"
WATTAGE"1/16W"
PACK_TYPE"0402";
"A"
$PN"1"32;
"B"
$PN"2"29;
%"RES"
"2","(-1275,2025)","0","mstr_discrete","I270";
;
ROOM"PVPP_KLM_VR"
CDS_LOCATION"R4G7"
$SEC"1"
CDS_SEC"1"
SPOF"TRUE"
REUSE_ID"9"
BOM_COST"PVPP_KLM_VR"
CDS_LIB"mstr_discrete"
TOLERANCE"1%"
VALUE"20.0K"
LOCATION"R4G7"
PART_NUMBER"G21796-040"
PACK_TYPE"0402"
MATERIAL"CHIP"
WATTAGE"1/16W";
"A"
$PN"1"31;
"B"
$PN"2"32;
%"RES"
"1","(-1275,2775)","5","mstr_discrete","I271";
;
CDS_SEC"1"
SEC"1"
ROOM"PVPP_KLM_VR"
SPOF"TRUE"
SEC_TYPE"0402"
CDS_LIB"mstr_discrete"
CDS_LOCATION"R4G8"
PART_NUMBER"G21497-005"
VALUE"0.0"
WATTAGE"1/16W"
MATERIAL"CHIP"
PACK_TYPE"0402"
LOCATION"R4G8"
TOLERANCE"5%";
"B"
$PN"2"31;
"A"
$PN"1"5;
%"RES"
"1","(-2075,2300)","0","mstr_discrete","I272";
;
CDS_SEC"1"
SEC_TYPE"0402"
REUSE_ID"13"
CDS_LOCATION"R4G13"
SEC"1"
BOM_COST"PVPP_KLM_VR"
CDS_LIB"mstr_discrete"
ROOM"PVPP_KLM_VR"
PACK_TYPE"0402"
LOCATION"R4G13"
PART_NUMBER"G21796-242"
TOLERANCE"1.0%"
MATERIAL"CHIP"
WATTAGE"1/16W"
VALUE"7.87K";
"B"
$PN"2"32;
"A"
$PN"1"37;
%"CAP"
"2","(-2350,2675)","2","mstr_discrete","I273";
;
CDS_SEC"1"
SEC_TYPE"0402LF"
REUSE_ID"27"
BOM_COST"PVPP_KLM_VR"
SEC"1"
ROOM"PVPP_KLM_VR"
CDS_LOCATION"C4G6"
CDS_LIB"mstr_discrete"
TOLERANCE"5%"
MATERIAL"COG"
LOCATION"C4G6"
VALUE"100.0PF"
VOLTAGE"50V"
PACK_TYPE"0402LF"
PART_NUMBER"A36095-026";
"A"
$PN"1"32;
"B"
$PN"2"36;
%"CAP"
"2","(-2775,2300)","2","mstr_discrete","I274";
;
CDS_SEC"1"
SEC_TYPE"0402LF"
REUSE_ID"27"
SEC"1"
CDS_LIB"mstr_discrete"
CDS_LOCATION"C4G10"
ROOM"PVPP_KLM_VR"
BOM_COST"PVPP_KLM_VR"
PART_NUMBER"A36096-075"
VALUE"2200PF"
TOLERANCE"10%"
LOCATION"C4G10"
PACK_TYPE"0402LF"
VOLTAGE"50V"
MATERIAL"X7R";
"A"
$PN"1"37;
"B"
$PN"2"36;
%"RES"
"1","(-6000,2675)","0","mstr_discrete","I275";
;
CDS_SEC"1"
SEC"1"
SEC_TYPE"0402"
ROOM"PVCCIN_CPU0_VR"
CDS_LIB"mstr_discrete"
CDS_LOCATION"R4G4"
PACK_TYPE"0402"
TOLERANCE"5%"
LOCATION"R4G4"
MATERIAL"CHIP"
PART_NUMBER"G21497-005"
VALUE"0.0"
WATTAGE"1/16W";
"B"
$PN"2"46;
"A"
$PN"1"30;
%"AGND_SCSI"
"1","(-1275,1025)","0","mstr_symbols","I276";
;
CDS_LIB"mstr_symbols"
ROOM"PVPP_KLM_VR"
BODY_TYPE"PLUMBING"
BOM_COST"PVPP_KLM_VR"
VOLTAGE"0.0V"
HDL_POWER"AGND_PVPP_GHJ";
"A"29;
%"INDUCTOR"
"1","(-2175,3700)","0","mstr_discrete","I277";
;
CDS_SEC"1"
TOLERANCE"1%"
SEC_TYPE"SM"
REUSE_ID"30"
SEC"1"
BOM_COST"PVPP_GHJ_VR"
CDS_LIB"mstr_discrete"
ROOM"PVPP_GHJ_VR"
CDS_LOCATION"L4G1"
PACK_TYPE"SM"
PART_NUMBER"E13358-018"
LOCATION"L4G1"
MATERIAL"IND"
VALUE"0.47UH";
"INA\NAC"
$PN"1"34;
"INB\NAC"
$PN"2"5;
END.
